FILE_TYPE = CONNECTIVITY;
{Allegro Design Entry HDL 17.4-2019 S026 (4007227) 1/17/2022}
"PAGE_NUMBER" = 343;
0"NC";
1"GND\g";
2"GND\g";
3"P12V_AUX\g";
4"GND\g";
5"GND\g";
6"GND\g";
7"GND\g";
8"GND\g";
9"GND\g";
10"P12V_AUX\g";
11"GND\g";
12"GND\g";
13"GND\g";
14"GND\g";
15"GND\g";
16"GND\g";
17"GND\g";
18"OCP_V3_2_PRSNT1_R_N"CDS_PHYS_NET_NAME"OCP_V3_2_PRSNT1_R_N";
19"OCP_V3_2_PRSNT0_R_N"CDS_PHYS_NET_NAME"OCP_V3_2_PRSNT0_R_N";
20"P3V3_AUX\g";
21"P3V3_AUX\g";
22"OCP_V3_2_PRSNT2_R_N"CDS_PHYS_NET_NAME"OCP_V3_2_PRSNT2_R_N";
23"P3V3_OCP_V3_2_EN_R";
24"HP_LVC3_OCP_V3_2_P12V_PWRGD";
25"P12V_OCP_V3_2_BUF_EN_R";
26"P12V_OCP_V3_2_BUF_EN_R";
27"P3V3_AUX\g";
28"GND\g";
29"GND\g";
30"GND\g";
31"GND\g";
32"P3V3_AUX\g";
33"P12V_AUX\g";
34"GND\g";
35"P3V3_AUX\g";
36"GND\g";
37"P3V3_AUX\g";
38"GND\g";
39"P3V3_AUX\g";
40"P3V3_OCP_V3_2_R\g";
41"GND\g";
42"P3V3_AUX\g";
43"P12V_OCP_V3_2\g";
44"GND\g";
45"P3V3_OCP_EN_2_R";
46"HP_LVC3_OCP_V3_2_P12V_PWRGD";
47"P12V_OCP_2_EN_G";
48"P12V_OCP_EN_2_R";
49"P12V_OCP_V3_2_EN_R";
50"P12V_OCP_UV_2_R";
51"P12V_OCP_VCC_2";
52"P12V_OCP_UV_2";
53"P12V_OCP_OV_2";
54"P12V_OCP_REG_2";
55"P12V_OCP_V3_2_ISENSE_MAM_MAM";
56"P12V_OCP_CB_2";
57"P12V_OCP_FAULT_2";
58"P12V_OCP_PWRGD_2";
59"P12V_OCP_SENSE_2";
60"P12V_OCP_GATE_2";
61"P12V_OCP_V3_2_ISENSE_MAM_TIC";
62"P3V3_OCP_UV_2";
63"P3V3_OCP_OV_2";
64"P3V3_OCP_CB_2";
65"P3V3_OCP_2_EN_G";
66"P3V3_OCP_UV_2_R1";
67"P3V3_OCP_GATE_2";
68"P3V3_OCP_VCC_2";
69"P3V3_OCP_REG_2";
70"P3V3_OCP_FAULT_2";
71"P3V3_OCP_PWRGD_2";
72"OCP_V3_2_P3V3_PWRGD";
73"P3V3_OCP_SENSE_2";
74"HP_LVC3_OCP_V3_2_PRSNT2_PLD_N"CDS_PHYS_NET_NAME"HP_LVC3_OCP_V3_2_PRSNT2_N";
75"HP_LVC3_OCP_V3_2_PRSNT2_N_R"CDS_PHYS_NET_NAME"HP_LVC3_OCP_V3_2_PRSNT2_N_R";
76"OCP_V3_2_PRSNT3_R_N"CDS_PHYS_NET_NAME"OCP_V3_2_PRSNT3_R_N";
77"HP_LVC3_OCP_V3_2_PRSNT2_N";
%"MOSFET_NCH_DUAL"
"1","(-2800,5875)","0","pure_quanta","I10";
;
LOCATION"Q118"
$SEC"1"
CDS_SEC"1"
ROOM"NIC_P12V_MAM_TIC_BOM1"
VALUE"PJT138K"
PART_TYPE"SMLF"
MATERIAL"IC"
NEEDS_NO_SIZE"TRUE"
CDS_LMAN_SYM_OUTLINE"-150,150,150,-150"
CDS_LIB"pure_quanta"
PART_NUMBER"BAM138K0003";
"D1"
$PN"6"47;
"G1"
$PN"2"48;
"S1"
$PN"1"2;
%"GND"
"1","(3975,6925)","0","pure_quanta_power","I100";
;
CDS_LIB"pure_quanta_power"
SIZE"1B"
HDL_POWER"GND";
"A<SIZE-1..0>\NAC"44;
%"Q_CAP"
"1","(3975,7225)","0","pure_quanta","I101";
;
LOCATION"PC2143"
$SEC"1"
CDS_SEC"1"
VALUE"10UF"
VOLTAGE"16V"
MATERIAL"X6S"
PACK_TYPE"C0805"
TOLERANCE"10%"
CDS_LIB"pure_quanta"
PART_NUMBER"CH6103KEA01";
"B"
$PN"2"44;
"A"
$PN"1"43;
%"UNIVERSAL_POWER"
"1","(3975,7525)","2","pure_quanta_power","I102";
;
HDL_POWER"P12V_OCP_V3_2"
CDS_LIB"pure_quanta_power";
"A"43;
%"GND"
"1","(3175,8650)","0","pure_quanta_power","I103";
;
CDS_LIB"pure_quanta_power"
SIZE"1B"
HDL_POWER"GND";
"A<SIZE-1..0>\NAC"1;
%"Q_CAP"
"1","(2400,8950)","0","pure_quanta","I104";
;
LOCATION"PC2149"
$SEC"1"
CDS_SEC"1"
VALUE"0.01UF"
VOLTAGE"50V"
MATERIAL"EMPTY"
ROOM"NIC_P3V3_BOM1"
PACK_TYPE"C0402"
TOLERANCE"10%"
CDS_LIB"pure_quanta"
PART_NUMBER"CH31006KB18";
"B"
$PN"2"67;
"A"
$PN"1"40;
%"Q_RES"
"2","(2675,8975)","0","pure_quanta","I105";
;
LOCATION"PR4523"
$SEC"1"
CDS_SEC"1"
WATTAGE"1/16W"
VALUE"10M"
PACK_TYPE"0402LF"
MATERIAL"CHIP"
ROOM"NIC_P3V3_BOM1"
TOLERANCE"1%"
CDS_LIB"pure_quanta"
PART_NUMBER"CS61002FB02";
"A"
$PN"1"40;
"B"
$PN"2"67;
%"SCHOTTKY_AC"
"1","(2800,9575)","1","pure_quanta","I106";
;
LOCATION"PD109"
$SEC"1"
CDS_SEC"1"
VALUE"B340A-13-F"
CDS_LMAN_SYM_OUTLINE"-75,50,75,-50"
CDS_LIB"pure_quanta"
NEEDS_NO_SIZE"TRUE"
PART_TYPE"SMLF"
MATERIAL"IC"
PART_NUMBER"BC000340Z30";
"C"
$PN"C"40;
"A"
$PN"A"41;
%"Q_RES"
"2","(3425,8925)","0","pure_quanta","I107";
;
LOCATION"R3833"
$SEC"1"
CDS_SEC"1"
TOLERANCE"1%"
PACK_TYPE"0402LF"
MATERIAL"CHIP"
WATTAGE"1/16W"
VALUE"100K"
ROOM"NIC_P3V3_BOM1"
CDS_LIB"pure_quanta"
PART_NUMBER"CS41002FB09";
"A"
$PN"1"42;
"B"
$PN"2"70;
%"Q_CAP"
"1","(3300,9550)","0","pure_quanta","I108";
;
LOCATION"PC2137"
$SEC"1"
CDS_SEC"1"
VALUE"0.1UF"
MATERIAL"X7R"
VOLTAGE"25V"
PACK_TYPE"0402"
TOLERANCE"10%"
CDS_LIB"pure_quanta"
PART_NUMBER"CH4104K1B00";
"B"
$PN"2"41;
"A"
$PN"1"40;
%"VCCAUX15"
"1","(3625,9250)","0","pure_quanta_power","I110";
;
HDL_POWER"P3V3_AUX"
CDS_LIB"pure_quanta_power";
"A"42;
%"GND"
"1","(3875,9250)","0","pure_quanta_power","I111";
;
SIZE"1B"
CDS_LIB"pure_quanta_power"
HDL_POWER"GND";
"A<SIZE-1..0>\NAC"41;
%"Q_CAP"
"1","(3875,9550)","0","pure_quanta","I112";
;
LOCATION"PC2142"
$SEC"1"
CDS_SEC"1"
MATERIAL"X6S"
VOLTAGE"16V"
VALUE"10UF"
PACK_TYPE"C0805"
CDS_LIB"pure_quanta"
TOLERANCE"10%"
PART_NUMBER"CH6103KEA01";
"B"
$PN"2"41;
"A"
$PN"1"40;
%"UNIVERSAL_POWER"
"1","(3875,9850)","2","pure_quanta_power","I113";
;
HDL_POWER"P3V3_OCP_V3_2_R"
CDS_LIB"pure_quanta_power";
"A"40;
%"UNIVERSAL_POWER"
"1","(1925,5225)","0","pure_quanta_power","I115";
;
HDL_POWER"P3V3_AUX"
CDS_LIB"pure_quanta_power";
"A"39;
%"Q_RES"
"1","(425,4275)","0","pure_quanta","I116";
;
LOCATION"R1191"
$SEC"1"
CDS_SEC"1"
WATTAGE"1/16W"
PACK_TYPE"0402LF"
TOLERANCE"5%"
MATERIAL"CHIP"
VALUE"0"
CDS_LIB"pure_quanta"
PART_NUMBER"CS00002JB13";
"B"
$PN"2"77;
"A"
$PN"1"75;
%"Q_RES"
"2","(1750,4950)","2","pure_quanta","I118";
;
LOCATION"R1192"
$SEC"1"
CDS_SEC"1"
MATERIAL"CHIP"
WATTAGE"1/16W"
TOLERANCE"1%"
PACK_TYPE"0402LF"
VALUE"1K"
CDS_LIB"pure_quanta"
PART_NUMBER"CS21002FB06";
"A"
$PN"1"39;
"B"
$PN"2"77;
%"Q_RES"
"1","(-3775,5825)","0","pure_quanta","I119";
;
LOCATION"R4059"
$SEC"1"
CDS_SEC"1"
TOLERANCE"5%"
VALUE"0"
MATERIAL"EMPTY"
ROOM"NIC_P12V_MAM_TIC_BOM1"
CDS_LIB"pure_quanta"
PACK_TYPE"0402LF"
WATTAGE"1/16W"
PART_NUMBER"CS00002JB13";
"B"
$PN"2"48;
"A"
$PN"1"49;
%"Q_RES"
"2","(-3075,5550)","2","pure_quanta","I120";
;
LOCATION"R6060"
$SEC"1"
CDS_SEC"1"
ROOM"NIC_P12V_MAM_TIC_BOM1"
PACK_TYPE"0402LF"
WATTAGE"1/16W"
TOLERANCE"5%"
VALUE"4.7K"
MATERIAL"EMPTY"
CDS_LIB"pure_quanta"
PART_NUMBER"CS24702JB10";
"A"
$PN"1"48;
"B"
$PN"2"16;
%"Q_RES"
"2","(-2725,7500)","2","pure_quanta","I121";
;
LOCATION"R4066"
$SEC"1"
CDS_SEC"1"
ROOM"NIC_P3V3_BOM1"
PACK_TYPE"0402LF"
WATTAGE"1/16W"
TOLERANCE"5%"
VALUE"4.7K"
MATERIAL"EMPTY"
CDS_LIB"pure_quanta"
PART_NUMBER"CS24702JB10";
"A"
$PN"1"45;
"B"
$PN"2"8;
%"Q_RES"
"1","(-3175,7825)","0","pure_quanta","I122";
;
LOCATION"R4060"
$SEC"1"
CDS_SEC"1"
TOLERANCE"5%"
MATERIAL"EMPTY"
VALUE"0"
ROOM"NIC_P3V3_BOM1"
WATTAGE"1/16W"
PACK_TYPE"0402LF"
CDS_LIB"pure_quanta"
PART_NUMBER"CS00002JB13";
"B"
$PN"2"45;
"A"
$PN"1"23;
%"Q_RES"
"1","(-3250,6350)","0","pure_quanta","I123";
;
LOCATION"R1181"
$SEC"1"
CDS_SEC"1"
MATERIAL"CHIP"
TOLERANCE"5%"
VALUE"0"
ROOM"NIC_P12V_MAM_TIC_BOM1"
CDS_LIB"pure_quanta"
WATTAGE"1/16W"
PACK_TYPE"0402LF"
PART_NUMBER"CS00002JB13";
"B"
$PN"2"48;
"A"
$PN"1"26;
%"Q_RES"
"1","(3075,8625)","0","pure_quanta","I127";
;
LOCATION"R3832"
$SEC"1"
CDS_SEC"1"
ROOM"NIC_P3V3_BOM1"
WATTAGE"1/16W"
MATERIAL"EMPTY"
TOLERANCE"5%"
VALUE"0"
PACK_TYPE"0402LF"
CDS_LIB"pure_quanta"
PART_NUMBER"CS00002JB13";
"B"
$PN"2"72;
"A"
$PN"1"71;
%"Q_RES"
"2","(4100,8925)","0","pure_quanta","I128";
;
LOCATION"R3826"
$SEC"1"
CDS_SEC"1"
ROOM"NIC_P3V3_BOM1"
PACK_TYPE"0402LF"
TOLERANCE"1%"
MATERIAL"EMPTY"
WATTAGE"1/16W"
VALUE"100K"
CDS_LIB"pure_quanta"
PART_NUMBER"CS41002FB09";
"A"
$PN"1"42;
"B"
$PN"2"72;
%"Q_RES"
"1","(-3175,8275)","0","pure_quanta","I129";
;
LOCATION"R1182"
$SEC"1"
CDS_SEC"1"
MATERIAL"EMPTY"
TOLERANCE"5%"
VALUE"0"
ROOM"NIC_P3V3_BOM1"
CDS_LIB"pure_quanta"
WATTAGE"1/16W"
PACK_TYPE"0402LF"
PART_NUMBER"CS00002JB13";
"B"
$PN"2"45;
"A"
$PN"1"24;
%"GND"
"1","(-2750,5550)","0","pure_quanta_power","I13";
;
SIZE"1B"
CDS_LIB"pure_quanta_power"
HDL_POWER"GND";
"A<SIZE-1..0>\NAC"2;
%"Q_RES"
"1","(-3100,8550)","0","pure_quanta","I130";
;
LOCATION"R1520"
$SEC"1"
CDS_SEC"1"
ROOM"NIC_P3V3_BOM1"
MATERIAL"CHIP"
VALUE"0"
TOLERANCE"5%"
CDS_LIB"pure_quanta"
WATTAGE"1/16W"
PACK_TYPE"0402LF"
PART_NUMBER"CS00002JB13";
"B"
$PN"2"45;
"A"
$PN"1"25;
%"Q_RES"
"2","(-2350,5375)","0","pure_quanta","I14";
;
LOCATION"R3133"
$SEC"1"
CDS_SEC"1"
TOLERANCE"1%"
VALUE"1K"
MATERIAL"CHIP"
WATTAGE"1/16W"
PACK_TYPE"0402LF"
CDS_LIB"pure_quanta"
PART_NUMBER"CS21002FB06";
"A"
$PN"1"20;
"B"
$PN"2"19;
%"UNIVERSAL_POWER"
"1","(-2300,5675)","0","pure_quanta_power","I15";
;
HDL_POWER"P3V3_AUX"
CDS_LIB"pure_quanta_power";
"A"20;
%"Q_RES"
"2","(-2075,5375)","0","pure_quanta","I16";
;
LOCATION"R3135"
$SEC"1"
CDS_SEC"1"
MATERIAL"CHIP"
WATTAGE"1/16W"
TOLERANCE"1%"
VALUE"1K"
PACK_TYPE"0402LF"
CDS_LIB"pure_quanta"
PART_NUMBER"CS21002FB06";
"A"
$PN"1"20;
"B"
$PN"2"18;
%"Q_RES"
"2","(-2750,6475)","0","pure_quanta","I17";
;
LOCATION"R4065"
$SEC"1"
CDS_SEC"1"
ROOM"NIC_P12V_MAM_TIC_BOM1"
MATERIAL"CHIP"
TOLERANCE"1%"
WATTAGE"1/16W"
VALUE"10K"
PACK_TYPE"0402LF"
CDS_LIB"pure_quanta"
PART_NUMBER"CS31002FB08";
"A"
$PN"1"3;
"B"
$PN"2"47;
%"UNIVERSAL_POWER"
"1","(-2750,6725)","0","pure_quanta_power","I18";
;
HDL_POWER"P12V_AUX"
CDS_LIB"pure_quanta_power";
"A"3;
%"MOSFET_NCH_DUAL"
"2","(-1775,6200)","0","pure_quanta","I19";
;
LOCATION"Q118"
$SEC"2"
CDS_SEC"2"
MATERIAL"IC"
ROOM"NIC_P12V_MAM_TIC_BOM1"
PART_TYPE"SMLF"
VALUE"PJT138K"
CDS_LIB"pure_quanta"
CDS_LMAN_SYM_OUTLINE"-150,150,150,-150"
NEEDS_NO_SIZE"TRUE"
PART_NUMBER"BAM138K0003";
"S2"
$PN"4"4;
"G2"
$PN"5"47;
"D2"
$PN"3"50;
%"GND"
"1","(-1725,5900)","0","pure_quanta_power","I20";
;
CDS_LIB"pure_quanta_power"
SIZE"1B"
HDL_POWER"GND";
"A<SIZE-1..0>\NAC"4;
%"UNIVERSAL_GND"
"1","(-1550,3875)","0","pure_quanta_power","I21";
;
CDS_LIB"pure_quanta_power"
HDL_POWER"GND";
"A"38;
%"74LVC2G07DW7"
"1","(-1150,4175)","0","pure_quanta","I22";
;
LOCATION"U59"
$SEC"1"
CDS_SEC"1"
VALUE"74LVC2G07DW-7"
PART_TYPE"SMLF"
MATERIAL"IC"
NEEDS_NO_SIZE"TRUE"
CDS_LMAN_SYM_OUTLINE"-175,100,175,-100"
CDS_LIB"pure_quanta"
PART_NUMBER"AL002G07003";
"VCC"
$PN"5"37;
"GND"
$PN"2"38;
"2Y"
$PN"4"75;
"1Y"
$PN"6"75;
"2A"
$PN"3"76;
"1A"
$PN"1"22;
%"Q_CAP"
"1","(-475,4000)","0","pure_quanta","I23";
;
LOCATION"C1810"
$SEC"1"
CDS_SEC"1"
MATERIAL"X7R"
PACK_TYPE"0402"
TOLERANCE"10%"
VOLTAGE"25V"
VALUE"0.1UF"
CDS_LIB"pure_quanta"
PART_NUMBER"CH4104K1B00";
"B"
$PN"2"5;
"A"
$PN"1"37;
%"UNIVERSAL_GND"
"1","(-475,3800)","0","pure_quanta_power","I24";
;
CDS_LIB"pure_quanta_power"
HDL_POWER"GND";
"A"5;
%"UNIVERSAL_GND"
"1","(-475,4700)","0","pure_quanta_power","I25";
;
CDS_LIB"pure_quanta_power"
HDL_POWER"GND";
"A"6;
%"UNIVERSAL_POWER"
"1","(-475,4275)","0","pure_quanta_power","I26";
;
HDL_POWER"P3V3_AUX"
CDS_LIB"pure_quanta_power";
"A"37;
%"UNIVERSAL_GND"
"1","(-1550,4800)","0","pure_quanta_power","I27";
;
CDS_LIB"pure_quanta_power"
HDL_POWER"GND";
"A"36;
%"74LVC2G07DW7"
"1","(-1150,5075)","0","pure_quanta","I28";
;
LOCATION"U58"
$SEC"1"
CDS_SEC"1"
VALUE"74LVC2G07DW-7"
MATERIAL"IC"
PART_TYPE"SMLF"
NEEDS_NO_SIZE"TRUE"
CDS_LMAN_SYM_OUTLINE"-175,100,175,-100"
CDS_LIB"pure_quanta"
PART_NUMBER"AL002G07003";
"VCC"
$PN"5"35;
"GND"
$PN"2"36;
"2Y"
$PN"4"75;
"1Y"
$PN"6"75;
"2A"
$PN"3"18;
"1A"
$PN"1"19;
%"Q_CAP"
"1","(-475,4900)","0","pure_quanta","I29";
;
LOCATION"C1809"
$SEC"1"
CDS_SEC"1"
TOLERANCE"10%"
MATERIAL"X7R"
PACK_TYPE"0402"
VOLTAGE"25V"
VALUE"0.1UF"
CDS_LIB"pure_quanta"
PART_NUMBER"CH4104K1B00";
"B"
$PN"2"6;
"A"
$PN"1"35;
%"UNIVERSAL_POWER"
"1","(-475,5175)","0","pure_quanta_power","I30";
;
HDL_POWER"P3V3_AUX"
CDS_LIB"pure_quanta_power";
"A"35;
%"Q_RES"
"2","(-150,5775)","0","pure_quanta","I31";
;
LOCATION"PR3828"
$SEC"1"
CDS_SEC"1"
TOLERANCE"1%"
PACK_TYPE"0402LF"
VALUE"15K"
MATERIAL"CHIP"
WATTAGE"1/16W"
ROOM"NIC_P12V_MAM_TIC_BOM1"
CDS_LIB"pure_quanta"
PART_NUMBER"CS31502FB05";
"A"
$PN"1"53;
"B"
$PN"2"7;
%"GND"
"1","(-150,5525)","0","pure_quanta_power","I32";
;
SIZE"1B"
CDS_LIB"pure_quanta_power"
HDL_POWER"GND";
"A<SIZE-1..0>\NAC"7;
%"Q_RES"
"1","(-750,6400)","0","pure_quanta","I33";
;
LOCATION"R3827"
$SEC"1"
CDS_SEC"1"
ROOM"NIC_P12V_MAM_TIC_BOM1"
VALUE"0"
TOLERANCE"5%"
WATTAGE"1/16W"
MATERIAL"CHIP"
PACK_TYPE"0402LF"
CDS_LIB"pure_quanta"
PART_NUMBER"CS00002JB13";
"B"
$PN"2"52;
"A"
$PN"1"50;
%"GND"
"1","(-725,6650)","0","pure_quanta_power","I34";
;
CDS_LIB"pure_quanta_power"
SIZE"1B"
HDL_POWER"GND";
"A<SIZE-1..0>\NAC"34;
%"Q_RES"
"2","(-150,6050)","0","pure_quanta","I35";
;
LOCATION"PR3806"
$SEC"1"
CDS_SEC"1"
ROOM"NIC_P12V_MAM_TIC_BOM1"
TOLERANCE"1%"
PACK_TYPE"0402LF"
MATERIAL"CHIP"
WATTAGE"1/16W"
VALUE"6.8K"
CDS_LIB"pure_quanta"
PART_NUMBER"CS26802FB02";
"A"
$PN"1"52;
"B"
$PN"2"53;
%"Q_RES"
"2","(-150,6725)","0","pure_quanta","I36";
;
LOCATION"PR3805"
$SEC"1"
CDS_SEC"1"
ROOM"NIC_P12V_MAM_TIC_BOM1"
VALUE"160K"
TOLERANCE"1%"
PACK_TYPE"0402LF"
WATTAGE"1/16W"
MATERIAL"CHIP"
CDS_LIB"pure_quanta"
PART_NUMBER"CS41602FB05";
"A"
$PN"1"33;
"B"
$PN"2"52;
%"GND"
"1","(-2725,7275)","0","pure_quanta_power","I39";
;
SIZE"1B"
CDS_LIB"pure_quanta_power"
HDL_POWER"GND";
"A<SIZE-1..0>\NAC"8;
%"Q_RES"
"2","(-2525,4475)","0","pure_quanta","I4";
;
LOCATION"R3134"
$SEC"1"
CDS_SEC"1"
WATTAGE"1/16W"
TOLERANCE"1%"
VALUE"1K"
MATERIAL"CHIP"
PACK_TYPE"0402LF"
CDS_LIB"pure_quanta"
PART_NUMBER"CS21002FB06";
"A"
$PN"1"21;
"B"
$PN"2"22;
%"GND"
"1","(-2225,7525)","0","pure_quanta_power","I41";
;
CDS_LIB"pure_quanta_power"
SIZE"1B"
HDL_POWER"GND";
"A<SIZE-1..0>\NAC"9;
%"MOSFET_NCH_DUAL"
"1","(-2275,7875)","0","pure_quanta","I42";
;
LOCATION"Q119"
$SEC"1"
CDS_SEC"1"
VALUE"PJT138K"
MATERIAL"IC"
PART_TYPE"SMLF"
ROOM"NIC_P3V3_BOM1"
NEEDS_NO_SIZE"TRUE"
CDS_LMAN_SYM_OUTLINE"-150,150,150,-150"
CDS_LIB"pure_quanta"
PART_NUMBER"BAM138K0003";
"D1"
$PN"6"65;
"G1"
$PN"2"45;
"S1"
$PN"1"9;
%"Q_RES"
"2","(-2225,8475)","0","pure_quanta","I43";
;
LOCATION"R4067"
$SEC"1"
CDS_SEC"1"
VALUE"10K"
WATTAGE"1/16W"
PACK_TYPE"0402LF"
ROOM"NIC_P3V3_BOM1"
TOLERANCE"1%"
MATERIAL"CHIP"
CDS_LIB"pure_quanta"
PART_NUMBER"CS31002FB08";
"A"
$PN"1"10;
"B"
$PN"2"65;
%"UNIVERSAL_POWER"
"1","(-2225,8725)","0","pure_quanta_power","I44";
;
HDL_POWER"P12V_AUX"
CDS_LIB"pure_quanta_power";
"A"10;
%"MOSFET_NCH_DUAL"
"2","(-1575,8250)","0","pure_quanta","I45";
;
LOCATION"Q119"
$SEC"2"
CDS_SEC"2"
PART_TYPE"SMLF"
MATERIAL"IC"
VALUE"PJT138K"
ROOM"NIC_P3V3_BOM1"
NEEDS_NO_SIZE"TRUE"
CDS_LMAN_SYM_OUTLINE"-150,150,150,-150"
CDS_LIB"pure_quanta"
PART_NUMBER"BAM138K0003";
"S2"
$PN"4"11;
"G2"
$PN"5"65;
"D2"
$PN"3"66;
%"GND"
"1","(-1525,7900)","0","pure_quanta_power","I46";
;
CDS_LIB"pure_quanta_power"
SIZE"1B"
HDL_POWER"GND";
"A<SIZE-1..0>\NAC"11;
%"DIODE_TVS"
"1","(-875,7025)","1","pure_quanta","I47";
;
LOCATION"PD107"
$SEC"1"
CDS_SEC"1"
MATERIAL"IC"
VALUE"SMF14A"
CDS_LIB"pure_quanta"
CDS_LMAN_SYM_OUTLINE"-100,50,100,-50"
PART_TYPE"SMLF"
PIN_NAMES_ROTATE"True"
PART_NUMBER"BCSMF14AZ01";
"C"
$PN"C"
Pin_Length"Short"33;
"A"
$PN"A"34;
%"UNIVERSAL_POWER"
"1","(-725,7375)","0","pure_quanta_power","I48";
;
HDL_POWER"P12V_AUX"
CDS_LIB"pure_quanta_power";
"A"33;
%"Q_CAP"
"1","(-500,7025)","0","pure_quanta","I49";
;
LOCATION"PC2139"
$SEC"1"
CDS_SEC"1"
MATERIAL"X6S"
VOLTAGE"25V"
VALUE"1UF"
PACK_TYPE"C0402"
TOLERANCE"10%"
CDS_LIB"pure_quanta"
PART_NUMBER"CH5104KEB02";
"B"
$PN"2"34;
"A"
$PN"1"33;
%"UNIVERSAL_POWER"
"1","(-2525,4775)","0","pure_quanta_power","I5";
;
HDL_POWER"P3V3_AUX"
CDS_LIB"pure_quanta_power";
"A"21;
%"Q_RES"
"1","(-525,8725)","0","pure_quanta","I50";
;
LOCATION"R3807"
$SEC"1"
CDS_SEC"1"
PACK_TYPE"0402LF"
TOLERANCE"5%"
WATTAGE"1/16W"
ROOM"NIC_P3V3_BOM1"
VALUE"0"
MATERIAL"CHIP"
CDS_LIB"pure_quanta"
PART_NUMBER"CS00002JB13";
"B"
$PN"2"62;
"A"
$PN"1"66;
%"Q_RES"
"2","(-25,8100)","0","pure_quanta","I51";
;
LOCATION"PR3812"
$SEC"1"
CDS_SEC"1"
ROOM"NIC_P3V3_BOM1"
WATTAGE"1/16W"
MATERIAL"CHIP"
VALUE"15K"
TOLERANCE"1%"
PACK_TYPE"0402LF"
CDS_LIB"pure_quanta"
PART_NUMBER"CS31502FB05";
"A"
$PN"1"63;
"B"
$PN"2"12;
%"GND"
"1","(-25,7850)","0","pure_quanta_power","I52";
;
CDS_LIB"pure_quanta_power"
SIZE"1B"
HDL_POWER"GND";
"A<SIZE-1..0>\NAC"12;
%"Q_RES"
"2","(-25,8375)","0","pure_quanta","I53";
;
LOCATION"PR3829"
$SEC"1"
CDS_SEC"1"
PACK_TYPE"0402LF"
WATTAGE"1/16W"
VALUE"7.15K"
MATERIAL"CHIP"
TOLERANCE"1%"
ROOM"NIC_P3V3_BOM1"
CDS_LIB"pure_quanta"
PART_NUMBER"CS27152FB03";
"A"
$PN"1"62;
"B"
$PN"2"63;
%"GND"
"1","(-375,9075)","0","pure_quanta_power","I54";
;
CDS_LIB"pure_quanta_power"
SIZE"1B"
HDL_POWER"GND";
"A<SIZE-1..0>\NAC"13;
%"Q_CAP"
"1","(-375,9350)","0","pure_quanta","I55";
;
LOCATION"PC2140"
$SEC"1"
CDS_SEC"1"
MATERIAL"X6S"
VALUE"1UF"
VOLTAGE"25V"
PACK_TYPE"C0402"
CDS_LIB"pure_quanta"
TOLERANCE"10%"
PART_NUMBER"CH5104KEB02";
"B"
$PN"2"13;
"A"
$PN"1"32;
%"Q_RES"
"2","(-25,9100)","0","pure_quanta","I56";
;
LOCATION"PR3795"
$SEC"1"
CDS_SEC"1"
ROOM"NIC_P3V3_BOM1"
TOLERANCE"1%"
VALUE"25.5K"
PACK_TYPE"0402LF"
WATTAGE"1/16W"
MATERIAL"CHIP"
CDS_LIB"pure_quanta"
PART_NUMBER"CS32552FB06";
"A"
$PN"1"32;
"B"
$PN"2"62;
%"UNIVERSAL_POWER"
"1","(-375,9700)","0","pure_quanta_power","I57";
;
HDL_POWER"P3V3_AUX"
CDS_LIB"pure_quanta_power";
"A"32;
%"Q_RES"
"1","(425,4525)","0","pure_quanta","I59";
;
LOCATION"R3142"
$SEC"1"
CDS_SEC"1"
TOLERANCE"5%"
VALUE"0"
MATERIAL"CHIP"
WATTAGE"1/16W"
PACK_TYPE"0402LF"
CDS_LIB"pure_quanta"
PART_NUMBER"CS00002JB13";
"B"
$PN"2"74;
"A"
$PN"1"75;
%"Q_RES"
"2","(-2300,4475)","0","pure_quanta","I6";
;
LOCATION"R3136"
$SEC"1"
CDS_SEC"1"
PACK_TYPE"0402LF"
MATERIAL"CHIP"
VALUE"1K"
TOLERANCE"1%"
WATTAGE"1/16W"
CDS_LIB"pure_quanta"
PART_NUMBER"CS21002FB06";
"A"
$PN"1"21;
"B"
$PN"2"76;
%"GND"
"1","(700,5500)","0","pure_quanta_power","I62";
;
SIZE"1B"
CDS_LIB"pure_quanta_power"
HDL_POWER"GND";
"A<SIZE-1..0>\NAC"31;
%"Q_RES"
"2","(700,5800)","0","pure_quanta","I63";
;
LOCATION"PR3821"
$SEC"1"
CDS_SEC"1"
PACK_TYPE"0402LF"
VALUE"30.1K"
WATTAGE"1/16W"
TOLERANCE"1%"
MATERIAL"CHIP"
ROOM"NIC_P12V_MAM_TIC_BOM1"
CDS_LIB"pure_quanta"
PART_NUMBER"CS33012FB03";
"A"
$PN"1"56;
"B"
$PN"2"31;
%"GND"
"1","(175,6225)","0","pure_quanta_power","I64";
;
CDS_LIB"pure_quanta_power"
SIZE"1B"
HDL_POWER"GND";
"A<SIZE-1..0>\NAC"14;
%"Q_CAP"
"1","(175,6600)","0","pure_quanta","I65";
;
LOCATION"PC2098"
$SEC"1"
CDS_SEC"1"
MATERIAL"X6S"
VALUE"1UF"
VOLTAGE"25V"
ROOM"NIC_P12V_MAM_TIC_BOM1"
PACK_TYPE"C0402"
TOLERANCE"10%"
CDS_LIB"pure_quanta"
PART_NUMBER"CH5104KEB02";
"B"
$PN"2"14;
"A"
$PN"1"51;
%"Q_CAP"
"1","(400,6300)","1","pure_quanta","I66";
;
LOCATION"PC2146"
$SEC"1"
CDS_SEC"1"
VOLTAGE"25V"
VALUE"1UF"
PACK_TYPE"C0402"
ROOM"NIC_P12V_MAM_TIC_BOM1"
TOLERANCE"10%"
CDS_LIB"pure_quanta"
MATERIAL"X6S"
PART_NUMBER"CH5104KEB02";
"B"
$PN"2"54;
"A"
$PN"1"14;
%"MAX15090BEWIT"
"1","(1450,6300)","0","pure_quanta","I67";
;
LOCATION"PU201"
$SEC"1"
CDS_SEC"1"
VALUE"MAX15090BEWI+T"
PART_TYPE"SMLF"
ROOM"NIC_P12V_MAM_TIC_BOM1"
MATERIAL"IC"
CDS_LMAN_SYM_OUTLINE"-250,550,250,-550"
PIN_NAMES_ROTATE"True"
CDS_LIB"pure_quanta"
PART_NUMBER"AL015080B00";
"PG"
$PN"D7"58;
"FAULT# \B"
$PN"C7"57;
"GND_C2"
$PN"C2"30;
"GND_C1"
$PN"C1"30;
"GND_B2"
$PN"B2"30;
"CDLY"
$PN"A7"30;
"GATE"
$PN"A6"60;
"OUT_D6"
$PN"D6"43;
"OUT_D4"
$PN"D4"43;
"OUT_C6"
$PN"C6"43;
"OUT_C4"
$PN"C4"43;
"OUT_B6"
$PN"B6"43;
"OUT_B4"
$PN"B4"43;
"OUT_A4"
$PN"A4"43;
"ISENSE"
$PN"A1"59;
"OV"
$PN"D3"53;
"UV"
$PN"D2"52;
"REG"
$PN"D1"54;
"EN# \B"
$PN"B7"31;
"CB"
$PN"B1"56;
"IN_D5"
$PN"D5"33;
"IN_C5"
$PN"C5"33;
"IN_C3"
$PN"C3"33;
"IN_B5"
$PN"B5"33;
"IN_B3"
$PN"B3"33;
"IN_A5"
$PN"A5"33;
"IN_A3"
$PN"A3"33;
"VCC"
$PN"A2"51;
%"Q_RES"
"2","(1925,4950)","0","pure_quanta","I69";
;
LOCATION"R3147"
$SEC"1"
CDS_SEC"1"
VALUE"1K"
PACK_TYPE"0402LF"
TOLERANCE"1%"
WATTAGE"1/16W"
MATERIAL"CHIP"
CDS_LIB"pure_quanta"
PART_NUMBER"CS21002FB06";
"A"
$PN"1"39;
"B"
$PN"2"74;
%"GND"
"1","(2175,5625)","0","pure_quanta_power","I70";
;
CDS_LIB"pure_quanta_power"
SIZE"1B"
HDL_POWER"GND";
"A<SIZE-1..0>\NAC"30;
%"Q_RES"
"2","(2300,5925)","0","pure_quanta","I71";
;
LOCATION"PR3823"
$SEC"1"
CDS_SEC"1"
TOLERANCE"1%"
WATTAGE"1/16W"
MATERIAL"CHIP"
ROOM"NIC_P12V_MAM_TIC_BOM1"
PACK_TYPE"0402LF"
VALUE"845"
CDS_LIB"pure_quanta"
PART_NUMBER"CS18452FB01";
"A"
$PN"1"59;
"B"
$PN"2"30;
%"Q_CAP"
"1","(2275,6625)","0","pure_quanta","I72";
;
LOCATION"C40"
$SEC"1"
CDS_SEC"1"
VALUE"0.01UF"
VOLTAGE"50V"
MATERIAL"EMPTY"
ROOM"NIC_P12V_MAM_TIC_BOM1"
PACK_TYPE"C0402"
TOLERANCE"10%"
CDS_LIB"pure_quanta"
PART_NUMBER"CH31006KB18";
"B"
$PN"2"60;
"A"
$PN"1"43;
%"Q_RES"
"1","(3075,5975)","0","pure_quanta","I73";
;
LOCATION"R3868"
$SEC"1"
CDS_SEC"1"
ROOM"NIC_P12V_MAM_TIC_BOM1"
WATTAGE"1/16W"
TOLERANCE"5%"
VALUE"0"
MATERIAL"CHIP"
PACK_TYPE"0402LF"
CDS_LIB"pure_quanta"
PART_NUMBER"CS00002JB13";
"B"
$PN"2"61;
"A"
$PN"1"59;
%"Q_RES"
"1","(3075,6100)","0","pure_quanta","I74";
;
LOCATION"R3867"
$SEC"1"
CDS_SEC"1"
MATERIAL"EMPTY"
WATTAGE"1/16W"
VALUE"0"
TOLERANCE"5%"
PACK_TYPE"0402LF"
CDS_LIB"pure_quanta"
PART_NUMBER"CS00002JB13";
"B"
$PN"2"55;
"A"
$PN"1"59;
%"Q_CAP"
"1","(2850,6400)","1","pure_quanta","I75";
;
LOCATION"PC2150"
$SEC"1"
CDS_SEC"1"
PACK_TYPE"C0402"
VOLTAGE"50V"
VALUE"3900PF"
ROOM"NIC_P12V_MAM_TIC_BOM1"
CDS_LIB"pure_quanta"
MATERIAL"X7R"
TOLERANCE"10%"
PART_NUMBER"CH23906KB14";
"B"
$PN"2"15;
"A"
$PN"1"60;
%"Q_RES"
"2","(2575,6625)","0","pure_quanta","I76";
;
LOCATION"PR4522"
$SEC"1"
CDS_SEC"1"
VALUE"10M"
WATTAGE"1/16W"
PACK_TYPE"0402LF"
MATERIAL"CHIP"
TOLERANCE"1%"
ROOM"NIC_P12V_MAM_TIC_BOM1"
CDS_LIB"pure_quanta"
PART_NUMBER"CS61002FB02";
"A"
$PN"1"43;
"B"
$PN"2"60;
%"Q_RES"
"1","(2925,6300)","0","pure_quanta","I77";
;
LOCATION"R3831"
$SEC"1"
CDS_SEC"1"
MATERIAL"CHIP"
ROOM"NIC_P12V_MAM_TIC_BOM1"
PACK_TYPE"0402LF"
TOLERANCE"5%"
VALUE"0"
WATTAGE"1/16W"
CDS_LIB"pure_quanta"
PART_NUMBER"CS00002JB13";
"B"
$PN"2"46;
"A"
$PN"1"58;
%"GND"
"1","(3025,6325)","0","pure_quanta_power","I78";
;
CDS_LIB"pure_quanta_power"
SIZE"1B"
HDL_POWER"GND";
"A<SIZE-1..0>\NAC"15;
%"Q_RES"
"2","(3275,6550)","0","pure_quanta","I79";
;
LOCATION"R3816"
$SEC"1"
CDS_SEC"1"
VALUE"100K"
TOLERANCE"1%"
ROOM"NIC_P12V_MAM_TIC_BOM1"
PACK_TYPE"0402LF"
MATERIAL"CHIP"
WATTAGE"1/16W"
CDS_LIB"pure_quanta"
PART_NUMBER"CS41002FB09";
"A"
$PN"1"27;
"B"
$PN"2"57;
%"GND"
"1","(-3075,5275)","0","pure_quanta_power","I8";
;
CDS_LIB"pure_quanta_power"
SIZE"1B"
HDL_POWER"GND";
"A<SIZE-1..0>\NAC"16;
%"Q_RES"
"2","(3700,6550)","0","pure_quanta","I80";
;
LOCATION"R3825"
$SEC"1"
CDS_SEC"1"
VALUE"100K"
MATERIAL"CHIP"
TOLERANCE"1%"
WATTAGE"1/16W"
PACK_TYPE"0402LF"
ROOM"NIC_P12V_MAM_TIC_BOM1"
CDS_LIB"pure_quanta"
PART_NUMBER"CS41002FB09";
"A"
$PN"1"27;
"B"
$PN"2"46;
%"Q_RES"
"2","(175,7025)","0","pure_quanta","I84";
;
LOCATION"PR3830"
$SEC"1"
CDS_SEC"1"
PACK_TYPE"0402LF"
MATERIAL"CHIP"
ROOM"NIC_P12V_MAM_TIC_BOM1"
WATTAGE"1/16W"
TOLERANCE"1%"
VALUE"10"
CDS_LIB"pure_quanta"
PART_NUMBER"CS01002FB07";
"A"
$PN"1"33;
"B"
$PN"2"51;
%"GND"
"1","(300,8550)","0","pure_quanta_power","I85";
;
SIZE"1B"
CDS_LIB"pure_quanta_power"
HDL_POWER"GND";
"A<SIZE-1..0>\NAC"17;
%"Q_CAP"
"1","(525,8625)","1","pure_quanta","I86";
;
LOCATION"PC2147"
$SEC"1"
CDS_SEC"1"
VALUE"1UF"
VOLTAGE"25V"
ROOM"NIC_P3V3_BOM1"
PACK_TYPE"C0402"
MATERIAL"X6S"
CDS_LIB"pure_quanta"
TOLERANCE"10%"
PART_NUMBER"CH5104KEB02";
"B"
$PN"2"69;
"A"
$PN"1"17;
%"GND"
"1","(825,7825)","0","pure_quanta_power","I87";
;
SIZE"1B"
CDS_LIB"pure_quanta_power"
HDL_POWER"GND";
"A<SIZE-1..0>\NAC"29;
%"Q_RES"
"2","(825,8125)","0","pure_quanta","I88";
;
LOCATION"PR3822"
$SEC"1"
CDS_SEC"1"
PACK_TYPE"0402LF"
ROOM"NIC_P3V3_BOM1"
TOLERANCE"1%"
VALUE"5.36K"
MATERIAL"CHIP"
WATTAGE"1/16W"
CDS_LIB"pure_quanta"
PART_NUMBER"CS25362FB02";
"A"
$PN"1"64;
"B"
$PN"2"29;
%"MAX15090BEWIT"
"1","(1575,8625)","0","pure_quanta","I89";
;
LOCATION"PU200"
$SEC"1"
CDS_SEC"1"
PART_TYPE"SMLF"
ROOM"NIC_P3V3_BOM1"
VALUE"MAX15090BEWI+T"
MATERIAL"IC"
CDS_LIB"pure_quanta"
PIN_NAMES_ROTATE"True"
CDS_LMAN_SYM_OUTLINE"-250,550,250,-550"
PART_NUMBER"AL015080B00";
"PG"
$PN"D7"71;
"FAULT# \B"
$PN"C7"70;
"GND_C2"
$PN"C2"28;
"GND_C1"
$PN"C1"28;
"GND_B2"
$PN"B2"28;
"CDLY"
$PN"A7"28;
"GATE"
$PN"A6"67;
"OUT_D6"
$PN"D6"40;
"OUT_D4"
$PN"D4"40;
"OUT_C6"
$PN"C6"40;
"OUT_C4"
$PN"C4"40;
"OUT_B6"
$PN"B6"40;
"OUT_B4"
$PN"B4"40;
"OUT_A4"
$PN"A4"40;
"ISENSE"
$PN"A1"73;
"OV"
$PN"D3"63;
"UV"
$PN"D2"62;
"REG"
$PN"D1"69;
"EN# \B"
$PN"B7"29;
"CB"
$PN"B1"64;
"IN_D5"
$PN"D5"32;
"IN_C5"
$PN"C5"32;
"IN_C3"
$PN"C3"32;
"IN_B5"
$PN"B5"32;
"IN_B3"
$PN"B3"32;
"IN_A5"
$PN"A5"32;
"IN_A3"
$PN"A3"32;
"VCC"
$PN"A2"68;
%"Q_CAP"
"1","(300,8925)","0","pure_quanta","I90";
;
LOCATION"C39"
$SEC"1"
CDS_SEC"1"
ROOM"NIC_P3V3_BOM1"
VALUE"1UF"
MATERIAL"X6S"
VOLTAGE"25V"
PACK_TYPE"C0402"
TOLERANCE"10%"
CDS_LIB"pure_quanta"
PART_NUMBER"CH5104KEB02";
"B"
$PN"2"17;
"A"
$PN"1"68;
%"Q_RES"
"2","(300,9350)","0","pure_quanta","I91";
;
LOCATION"PR3782"
$SEC"1"
CDS_SEC"1"
WATTAGE"1/16W"
PACK_TYPE"0402LF"
MATERIAL"CHIP"
TOLERANCE"1%"
VALUE"10"
ROOM"NIC_P3V3_BOM1"
CDS_LIB"pure_quanta"
PART_NUMBER"CS01002FB07";
"A"
$PN"1"32;
"B"
$PN"2"68;
%"SCHOTTKY_AC"
"1","(2675,7250)","1","pure_quanta","I92";
;
LOCATION"PD108"
$SEC"1"
CDS_SEC"1"
VALUE"B340A-13-F"
MATERIAL"IC"
PART_TYPE"SMLF"
NEEDS_NO_SIZE"TRUE"
CDS_LIB"pure_quanta"
CDS_LMAN_SYM_OUTLINE"-75,50,75,-50"
PART_NUMBER"BC000340Z30";
"C"
$PN"C"43;
"A"
$PN"A"44;
%"GND"
"1","(2300,7950)","0","pure_quanta_power","I93";
;
SIZE"1B"
CDS_LIB"pure_quanta_power"
HDL_POWER"GND";
"A<SIZE-1..0>\NAC"28;
%"Q_RES"
"2","(2425,8275)","0","pure_quanta","I94";
;
LOCATION"PR3824"
$SEC"1"
CDS_SEC"1"
MATERIAL"CHIP"
TOLERANCE"1%"
VALUE"4.53K"
WATTAGE"1/16W"
PACK_TYPE"0402LF"
ROOM"NIC_P3V3_BOM1"
CDS_LIB"pure_quanta"
PART_NUMBER"CS24532FB03";
"A"
$PN"1"73;
"B"
$PN"2"28;
%"Q_CAP"
"1","(3000,8725)","1","pure_quanta","I95";
;
LOCATION"PC2151"
$SEC"1"
CDS_SEC"1"
VOLTAGE"50V"
PACK_TYPE"C0402"
VALUE"6800PF"
ROOM"NIC_P3V3_BOM1"
CDS_LIB"pure_quanta"
MATERIAL"X7R"
TOLERANCE"10%"
PART_NUMBER"CH2686K1B01";
"B"
$PN"2"1;
"A"
$PN"1"67;
%"Q_CAP"
"1","(3150,7225)","0","pure_quanta","I97";
;
LOCATION"PC2152"
$SEC"1"
CDS_SEC"1"
PACK_TYPE"0402"
MATERIAL"X7R"
VALUE"0.1UF"
VOLTAGE"25V"
CDS_LIB"pure_quanta"
TOLERANCE"10%"
PART_NUMBER"CH4104K1B00";
"B"
$PN"2"44;
"A"
$PN"1"43;
%"VCCAUX15"
"1","(3475,6900)","0","pure_quanta_power","I98";
;
HDL_POWER"P3V3_AUX"
CDS_LIB"pure_quanta_power";
"A"27;
%"Q_CAP"
"1","(3575,7225)","0","pure_quanta","I99";
;
LOCATION"PC2141"
$SEC"1"
CDS_SEC"1"
VALUE"22UF"
PACK_TYPE"C0805"
VOLTAGE"16V"
MATERIAL"X6S"
TOLERANCE"20%"
CDS_LIB"pure_quanta"
PART_NUMBER"CH6223MEA01";
"B"
$PN"2"44;
"A"
$PN"1"43;
END.
